#ISCELL
  logical_power bom_note *
  *
#ISCELL
  logical_power design_note *
  *
#ISCELL
  mstr_misc dns *
  *
#ISCELL
  pure_quanta quanta_title_block_c *
  *
#CELL
  pure_quanta q_cap *
  page182_i100
#CELL
  pure_quanta q_res *
  page182_i105
#ISCELL
  logical_power universal_gnd *
  page182_i106
#ISCELL
  standard offpage *
  page182_i107
#ISCELL
  standard offpage *
  page182_i108
#ISCELL
  standard offpage *
  page182_i120
#ISCELL
  standard offpage *
  page182_i123
#ISCELL
  standard offpage *
  page182_i124
#ISCELL
  standard offpage *
  page182_i125
#ISCELL
  standard tap *
  page182_i136
#ISCELL
  standard tap *
  page182_i137
#ISCELL
  standard tap *
  page182_i146
#ISCELL
  standard tap *
  page182_i147
#ISCELL
  standard tap *
  page182_i150
#ISCELL
  standard tap *
  page182_i151
#ISCELL
  standard offpage *
  page182_i154
#ISCELL
  standard offpage *
  page182_i155
#ISCELL
  standard offpage *
  page182_i158
#ISCELL
  standard offpage *
  page182_i159
#ISCELL
  standard offpage *
  page182_i160
#ISCELL
  standard offpage *
  page182_i161
#CELL
  pure_quanta q_res *
  page182_i162
#ISCELL
  standard offpage *
  page182_i163
#CELL
  pure_quanta q_res *
  page182_i164
#ISCELL
  logical_power universal_gnd *
  page182_i165
#CELL
  pure_quanta q_res *
  page182_i167
#ISCELL
  logical_power universal_gnd *
  page182_i172
#CELL
  pure_quanta q_res *
  page182_i173
#ISCELL
  logical_power universal_power *
  page182_i174
#ISCELL
  standard offpage *
  page182_i175
#CELL
  pure_quanta q_res *
  page182_i176
#ISCELL
  logical_power universal_power *
  page182_i177
#CELL
  pure_quanta sconn75k_apci0155p004a *
  page182_i178
#ISCELL
  standard offpage *
  page182_i231
#ISCELL
  standard tap *
  page182_i233
#ISCELL
  standard tap *
  page182_i234
#ISCELL
  standard tap *
  page182_i235
#ISCELL
  standard tap *
  page182_i236
#ISCELL
  standard tap *
  page182_i237
#ISCELL
  standard tap *
  page182_i238
#ISCELL
  standard offpage *
  page182_i244
#ISCELL
  standard offpage *
  page182_i245
#CELL
  pure_quanta q_res *
  page182_i247
#ISCELL
  standard offpage *
  page182_i248
#ISCELL
  logical_power universal_power *
  page182_i249
#ISCELL
  standard offpage *
  page182_i250
#ISCELL
  standard offpage *
  page182_i296
#CELL
  pure_quanta q_res *
  page182_i299
#ISCELL
  logical_power universal_power *
  page182_i300
#ISCELL
  logical_power universal_gnd *
  page182_i301
#ISCELL
  standard offpage *
  page182_i302
#CELL
  pure_quanta q_res *
  page182_i303
#ISCELL
  logical_power universal_gnd *
  page182_i304
#ISCELL
  logical_power universal_power *
  page182_i305
#CELL
  pure_quanta q_res *
  page182_i306
#ISCELL
  logical_power universal_power *
  page182_i307
#CELL
  pure_quanta q_cap *
  page182_i308
#ISCELL
  logical_power universal_gnd *
  page182_i309
#ISCELL
  logical_power universal_gnd *
  page182_i310
#ISCELL
  standard offpage *
  page182_i311
#CELL
  pure_quanta q_res *
  page182_i312
#ISCELL
  logical_power universal_gnd *
  page182_i313
#CELL
  pure_quanta 74lvc1g126se7 *
  page182_i315
#CELL
  pure_quanta q_res *
  page182_i317
#ISCELL
  standard offpage *
  page182_i318
#CELL
  pure_quanta q_res *
  page182_i320
#ISCELL
  standard offpage *
  page182_i322
#ISCELL
  logical_power universal_power *
  page182_i323
#CELL
  pure_quanta q_res *
  page182_i324
#ISCELL
  logical_power universal_power *
  page182_i325
#CELL
  pure_quanta q_cap *
  page182_i326
#CELL
  pure_quanta sn74lvc2g07dckr *
  page182_i327
#ISCELL
  logical_power universal_gnd *
  page182_i328
#ISCELL
  standard offpage *
  page182_i329
#ISCELL
  standard offpage *
  page182_i336
#CELL
  pure_quanta q_res *
  page182_i337
#ISCELL
  logical_power universal_power *
  page182_i338
#ISCELL
  standard offpage *
  page182_i340
#ISCELL
  logical_power universal_power *
  page182_i341
#CELL
  pure_quanta mosfet_nch_dual *
  page182_i342
#CELL
  pure_quanta mosfet_nch_dual *
  page182_i343
#CELL
  pure_quanta q_res *
  page182_i344
#CELL
  pure_quanta q_cap *
  page182_i88
#ISCELL
  logical_power universal_power *
  page182_i89
#CELL
  pure_quanta q_cap *
  page182_i90
#CELL
  pure_quanta q_cap *
  page182_i96
#CELL
  pure_quanta q_cap *
  page182_i97
#CELL
  pure_quanta q_cap *
  page182_i98
#ISCELL
  logical_power universal_gnd *
  page182_i99
